# S9S_MB_2U (Grand Teton) — schematic netlist excerpt (pin names and nets, part order shuffled) for the footprints in the layout excerpt that follows; sources: Cadence DE-HDL packaged netlist, KiCad conversion of 03242023_DA0F0TMBIJ0_F0T_Motherboard_J_brd_V01_OCP.brd

R3752  Q_RES  0 5% CHIP  pkg 0402LF  page 171 : A = E1S_0_P3V3_ADC_ALERT_R ; B = E1S_0_P3V3_ADC_ALERT
R3886  Q_RES  49.9 1% CHIP  pkg 0402LF  page 93 : A = I3C_SPD_DDREFGH_CPU0_LVC1_SCL_3 ; B = I3C_SPD_DDREFGH_CPU0_LVC1_SCL

(kicad_pcb
	(version 20260206)
	(generator "pcbnew")
	(generator_version "10.0")
	(general
		(thickness 1.6)
		(legacy_teardrops no)
	)
	(paper "A4")
	(title_block
		(title "03242023_DA0F0TMBIJ0_F0T_Motherboard_J_brd_V01_OCP.brd")
		(comment 1 "Grand Teton / footprints 5900-5901 of 6105")
	)
	(layers
		(0 "F.Cu" signal "TOP")
		(4 "In1.Cu" signal "GND")
		(6 "In2.Cu" signal "IN1")
		(8 "In3.Cu" signal "GND1")
		(10 "In4.Cu" signal "IN2")
		(12 "In5.Cu" signal "GND2")
		(14 "In6.Cu" signal "IN3")
		(16 "In7.Cu" signal "GND3")
		(18 "In8.Cu" signal "VCC")
		(20 "In9.Cu" signal "VCC1")
		(22 "In10.Cu" signal "GND4")
		(24 "In11.Cu" signal "IN4")
		(26 "In12.Cu" signal "GND5")
		(28 "In13.Cu" signal "IN5")
		(30 "In14.Cu" signal "GND6")
		(32 "In15.Cu" signal "IN6")
		(34 "In16.Cu" signal "GND7")
		(2 "B.Cu" signal "BOTTOM")
		(9 "F.Adhes" user "F.Adhesive")
		(11 "B.Adhes" user "B.Adhesive")
		(13 "F.Paste" user "Package Geometry/Pastemask Top")
		(15 "B.Paste" user "Package Geometry/Pastemask Bottom")
		(5 "F.SilkS" user "Ref Des/Silkscreen Top")
		(7 "B.SilkS" user "Ref Des/Silkscreen Bottom")
		(1 "F.Mask" user "Board Geometry/Soldermask Top")
		(3 "B.Mask" user "Board Geometry/Soldermask Bottom")
		(17 "Dwgs.User" user "User.Drawings")
		(19 "Cmts.User" user "User.Comments")
		(21 "Eco1.User" user "User.Eco1")
		(23 "Eco2.User" user "User.Eco2")
		(25 "Edge.Cuts" user "Board Geometry/Outline")
		(27 "Margin" user)
		(31 "F.CrtYd" user "Package Geometry/Place Bound Top")
		(29 "B.CrtYd" user "Package Geometry/Place Bound Bottom")
		(35 "F.Fab" user "Ref Des/Assembly Top")
		(33 "B.Fab" user "Ref Des/Assembly Bottom")
	)
	(footprint ""
		(layer "B.Cu")
		(at 420.152322 -318.05499 90)
		(property "Reference" "R3886"
			(at 0 0 90)
			(layer "B.SilkS")
			(hide yes)
			(effects
				(font
					(size 1.27 1.27)
				)
				(justify mirror)
			)
		)
		(property "Value" ""
			(at 0 0 90)
			(layer "B.Fab")
			(effects
				(font
					(size 1.27 1.27)
				)
				(justify mirror)
			)
		)
		(duplicate_pad_numbers_are_jumpers no)
		(fp_line
			(start 0.7874 -0.4064)
			(end -0.7874 -0.4064)
			(stroke
				(width 0.1524)
				(type default)
			)
			(layer "B.SilkS")
		)
		(fp_line
			(start -0.7874 -0.4064)
			(end -0.7874 0.4064)
			(stroke
				(width 0.1524)
				(type default)
			)
			(layer "B.SilkS")
		)
		(fp_line
			(start 0.7874 0.4064)
			(end 0.7874 -0.4064)
			(stroke
				(width 0.1524)
				(type default)
			)
			(layer "B.SilkS")
		)
		(fp_line
			(start -0.7874 0.4064)
			(end 0.7874 0.4064)
			(stroke
				(width 0.1524)
				(type default)
			)
			(layer "B.SilkS")
		)
		(fp_line
			(start 0.67945 -0.305054)
			(end 0.12065 -0.305054)
			(stroke
				(width 0.1)
				(type default)
			)
			(layer "B.Fab")
		)
		(fp_line
			(start 0.12065 -0.305054)
			(end 0.12065 -0.2794)
			(stroke
				(width 0.1)
				(type default)
			)
			(layer "B.Fab")
		)
		(fp_line
			(start -0.12065 -0.3048)
			(end -0.67945 -0.3048)
			(stroke
				(width 0.1)
				(type default)
			)
			(layer "B.Fab")
		)
		(fp_line
			(start -0.67945 -0.3048)
			(end -0.67945 0.3048)
			(stroke
				(width 0.1)
				(type default)
			)
			(layer "B.Fab")
		)
		(fp_line
			(start 0.12065 -0.2794)
			(end -0.12065 -0.2794)
			(stroke
				(width 0.1)
				(type default)
			)
			(layer "B.Fab")
		)
		(fp_line
			(start -0.12065 -0.2794)
			(end -0.12065 -0.3048)
			(stroke
				(width 0.1)
				(type default)
			)
			(layer "B.Fab")
		)
		(fp_line
			(start 0.12065 0.2794)
			(end 0.12065 0.3048)
			(stroke
				(width 0.1)
				(type default)
			)
			(layer "B.Fab")
		)
		(fp_line
			(start -0.120396 0.2794)
			(end 0.12065 0.2794)
			(stroke
				(width 0.1)
				(type default)
			)
			(layer "B.Fab")
		)
		(fp_line
			(start 0.67945 0.3048)
			(end 0.67945 -0.305054)
			(stroke
				(width 0.1)
				(type default)
			)
			(layer "B.Fab")
		)
		(fp_line
			(start 0.12065 0.3048)
			(end 0.67945 0.3048)
			(stroke
				(width 0.1)
				(type default)
			)
			(layer "B.Fab")
		)
		(fp_line
			(start -0.120396 0.3048)
			(end -0.120396 0.2794)
			(stroke
				(width 0.1)
				(type default)
			)
			(layer "B.Fab")
		)
		(fp_line
			(start -0.67945 0.3048)
			(end -0.120396 0.3048)
			(stroke
				(width 0.1)
				(type default)
			)
			(layer "B.Fab")
		)
		(pad "1" smd circle
			(at 0.40005 0 270)
			(size 0 0)
			(layers "B.Cu" "B.Mask" "B.Paste")
			(net "I3C_SPD_DDREFGH_CPU0_LVC1_SCL_3")
		)
		(pad "2" smd circle
			(at -0.40005 0 270)
			(size 0 0)
			(layers "B.Cu" "B.Mask" "B.Paste")
			(net "I3C_SPD_DDREFGH_CPU0_LVC1_SCL")
		)
	)
	(footprint ""
		(layer "B.Cu")
		(at 211.69503 -57.078372 -90)
		(property "Reference" "R3752"
			(at 0 0 90)
			(layer "B.SilkS")
			(hide yes)
			(effects
				(font
					(size 1.27 1.27)
				)
				(justify mirror)
			)
		)
		(property "Value" ""
			(at 0 0 90)
			(layer "B.Fab")
			(effects
				(font
					(size 1.27 1.27)
				)
				(justify mirror)
			)
		)
		(duplicate_pad_numbers_are_jumpers no)
		(fp_line
			(start -0.7874 0.4064)
			(end 0.7874 0.4064)
			(stroke
				(width 0.1524)
				(type default)
			)
			(layer "B.SilkS")
		)
		(fp_line
			(start 0.7874 0.4064)
			(end 0.7874 -0.4064)
			(stroke
				(width 0.1524)
				(type default)
			)
			(layer "B.SilkS")
		)
		(fp_line
			(start -0.7874 -0.4064)
			(end -0.7874 0.4064)
			(stroke
				(width 0.1524)
				(type default)
			)
			(layer "B.SilkS")
		)
		(fp_line
			(start 0.7874 -0.4064)
			(end -0.7874 -0.4064)
			(stroke
				(width 0.1524)
				(type default)
			)
			(layer "B.SilkS")
		)
		(fp_line
			(start -0.67945 0.3048)
			(end -0.120396 0.3048)
			(stroke
				(width 0.1)
				(type default)
			)
			(layer "B.Fab")
		)
		(fp_line
			(start -0.120396 0.3048)
			(end -0.120396 0.2794)
			(stroke
				(width 0.1)
				(type default)
			)
			(layer "B.Fab")
		)
		(fp_line
			(start 0.12065 0.3048)
			(end 0.67945 0.3048)
			(stroke
				(width 0.1)
				(type default)
			)
			(layer "B.Fab")
		)
		(fp_line
			(start 0.67945 0.3048)
			(end 0.67945 -0.305054)
			(stroke
				(width 0.1)
				(type default)
			)
			(layer "B.Fab")
		)
		(fp_line
			(start -0.120396 0.2794)
			(end 0.12065 0.2794)
			(stroke
				(width 0.1)
				(type default)
			)
			(layer "B.Fab")
		)
		(fp_line
			(start 0.12065 0.2794)
			(end 0.12065 0.3048)
			(stroke
				(width 0.1)
				(type default)
			)
			(layer "B.Fab")
		)
		(fp_line
			(start -0.12065 -0.2794)
			(end -0.12065 -0.3048)
			(stroke
				(width 0.1)
				(type default)
			)
			(layer "B.Fab")
		)
		(fp_line
			(start 0.12065 -0.2794)
			(end -0.12065 -0.2794)
			(stroke
				(width 0.1)
				(type default)
			)
			(layer "B.Fab")
		)
		(fp_line
			(start -0.67945 -0.3048)
			(end -0.67945 0.3048)
			(stroke
				(width 0.1)
				(type default)
			)
			(layer "B.Fab")
		)
		(fp_line
			(start -0.12065 -0.3048)
			(end -0.67945 -0.3048)
			(stroke
				(width 0.1)
				(type default)
			)
			(layer "B.Fab")
		)
		(fp_line
			(start 0.12065 -0.305054)
			(end 0.12065 -0.2794)
			(stroke
				(width 0.1)
				(type default)
			)
			(layer "B.Fab")
		)
		(fp_line
			(start 0.67945 -0.305054)
			(end 0.12065 -0.305054)
			(stroke
				(width 0.1)
				(type default)
			)
			(layer "B.Fab")
		)
		(pad "1" smd circle
			(at 0.40005 0 90)
			(size 0 0)
			(layers "B.Cu" "B.Mask" "B.Paste")
			(net "E1S_0_P3V3_ADC_ALERT_R")
		)
		(pad "2" smd circle
			(at -0.40005 0 90)
			(size 0 0)
			(layers "B.Cu" "B.Mask" "B.Paste")
			(net "E1S_0_P3V3_ADC_ALERT")
		)
	)
)
